# HONEY BADGER RISER CARD HS-1A BOM of 81.B0710.043G_20150213.xlsx — Primary and Alternate BOM of 81 (bom)
| Level | Parent Number | Part Number | Description | Green Factor | Life Cycle State | Manufacturer | Manufacturer Part Number | Source | BOM Usage | M/P Code | S/D | Qty | UoM | Location |
| 1 | 81.B0710.043G | 40.58D03.001 | LBL POLYIMIDE31.8*6.35 BARCODE | R2_SA;HF_SA;G_SA; | Released | LABELJET | 40.58D03.001 | Single |  | Purchase |  | 2 | PCS |  |
| 1 | 81.B0710.043G | 55.B0711.D06G | HONEY BADGER RISER CARD HS(D)-1A | N/A; | Released |  |  |  | E | Manufacture |  | 1 | PCS |  |
| 2 | 55.B0711.D06G | 20.50409.164 | CONN EDGE 164P AAA-PCI-006-G05 ,PA46 | R2_SA; | Released | LOTES | AAA-PCI-006-G05 | Single |  | Purchase | DIP | 1 | PCS | CN1 |
| 2 | 55.B0711.D06G | 55.B0711.S06G | HONEY BADGER RISER CARD HS(S)-1A | N/A; | Released |  |  |  | E | Manufacture | DIP | 1 | PCS |  |
| 3 | 55.B0711.S06G | 48.B0723.01A | PCB 13919-1A HONEY BADGER RISER CD 4L HA | R2_C; | Released | HANNSTAR |  | Single |  | Purchase | SMT | 1 | PCS |  |
| 1 | 81.B0710.043G | DP.B0710.S06 | DP HONEY BADGER RISER CARD-SB | N/A; | Released |  |  |  | E | Manufacture |  | 1 | PCS |  |
| 2 | DP.B0710.S06 | 40.54T01.001 | LBL CAUTION FOR P97AE | R2_SA;G_SA; | Released | CHENGMAY | 40.54T01.001 | Single |  | Purchase |  | 1 | PCS |  |
| 2 | DP.B0710.S06 | 42.58U02.001 | ESD BAG 80*150*0.08MM | R2_SA; | Released | TBD |  | Single |  | Purchase |  | 1 | PCS |  |
| 2 | DP.B0710.S06 | 44.56F02.011 | CTN AB B/R 390*323*176MM | R2_SA; | Released | TRICAN | Void | Single |  | Purchase |  | 1.5879999999999998E-2 | PCS |  |
| 2 | DP.B0710.S06 | 45.00005.312 | LBL CTN ART 124*40 B/W ALL | R2_SA;G_SA; | Released | CHENGMAY | 45.00005.312 | Single |  | Purchase |  | 3.175E-2 | PCS |  |
| 2 | DP.B0710.S06 | 46.30S02.001 | CORNER KRAFT PAPER 900*50*50*3 | R2_SA;HF_SA;G_SA; | Released | KHL;SAFEWAY | 46.30S02.001 | Multiple |  | Purchase |  | 7.1000000000000002E-4 | PCS |  |
| 2 | DP.B0710.S06 | 46.30S14.001 | CORNER KRAFT PAPER 950*50*50*3 | R2_SA;HF_SA;G_SA; | Released | MYS;MOONSHINE | 46.30S14.001 | Multiple |  | Purchase |  | 1.42E-3 | PCS |  |
| 2 | DP.B0710.S06 | 46.58F01.001 | CORNER PAPER1100*50*50*3 ORIGI | R2_SA;G_SA; | Released | COPLASCO;MYS | 46.58F01.001 | Multiple |  | Purchase |  | 7.1000000000000002E-4 | PCS |  |
| 2 | DP.B0710.S06 | 46.60A03.001 | SHEET AB FLUTE 1200*1000 NS110 | R2_SA;G_SA; | Released | GINYOUNG;TRICAN | 46.60A03.001 | Multiple |  | Purchase |  | 3.6000000000000002E-4 | PCS |  |
| 2 | DP.B0710.S06 | 47.51I02.001 | PARTITION B 312*137MM | R2_SA; | Released | TRICAN | Void | Single |  | Purchase |  | 0.12698999999999999 | PCS |  |
| 2 | DP.B0710.S06 | 47.56F04.001 | PARTITION B 379*137MM | R2_SA; | Released | TRICAN | Void | Single |  | Purchase |  | 0.15873000000000001 | PCS |  |
| 2 | DP.B0710.S06 | 47.57S22.001 | PALLET PLYWOOD 1200*1000*114MM | R2_SA; | Released | JIAMAO | Void | Single |  | Purchase |  | 3.6000000000000002E-4 | PCS |  |
| 2 | DP.B0710.S06 | 47.5M604.001 | CSN PAD EPE 375*310*10MM | R2_SA; | Released | TBD |  | Single |  | Purchase |  | 3.175E-2 | PCS |  |
